# S9S_MB_2U (Grand Teton) — schematic netlist excerpt (pin names and nets, part order shuffled) for the footprints in the layout excerpt that follows; sources: Cadence DE-HDL packaged netlist, KiCad conversion of 03242023_DA0F0TMBIJ0_F0T_Motherboard_J_brd_V01_OCP.brd

PR592  Q_RES  100 1% CHIP  pkg 0402LF  page 278 : A = VSENSE_PVCCD_HV_CPU0_DP ; B = PVCCD_HV_CPU0
R2995  Q_RES  33.2 1% CHIP  pkg 0402LF  page 241 : A = SMB_SML1_PMBUS_3V3AUX_PCH_SCL ; B = SMB_SML1_PMBUS_HSC_SCL_R3

(kicad_pcb
	(version 20260206)
	(generator "pcbnew")
	(generator_version "10.0")
	(general
		(thickness 1.6)
		(legacy_teardrops no)
	)
	(paper "A4")
	(title_block
		(title "03242023_DA0F0TMBIJ0_F0T_Motherboard_J_brd_V01_OCP.brd")
		(comment 1 "Grand Teton / footprints 3406-3407 of 6105")
	)
	(layers
		(0 "F.Cu" signal "TOP")
		(4 "In1.Cu" signal "GND")
		(6 "In2.Cu" signal "IN1")
		(8 "In3.Cu" signal "GND1")
		(10 "In4.Cu" signal "IN2")
		(12 "In5.Cu" signal "GND2")
		(14 "In6.Cu" signal "IN3")
		(16 "In7.Cu" signal "GND3")
		(18 "In8.Cu" signal "VCC")
		(20 "In9.Cu" signal "VCC1")
		(22 "In10.Cu" signal "GND4")
		(24 "In11.Cu" signal "IN4")
		(26 "In12.Cu" signal "GND5")
		(28 "In13.Cu" signal "IN5")
		(30 "In14.Cu" signal "GND6")
		(32 "In15.Cu" signal "IN6")
		(34 "In16.Cu" signal "GND7")
		(2 "B.Cu" signal "BOTTOM")
		(9 "F.Adhes" user "F.Adhesive")
		(11 "B.Adhes" user "B.Adhesive")
		(13 "F.Paste" user "Package Geometry/Pastemask Top")
		(15 "B.Paste" user "Package Geometry/Pastemask Bottom")
		(5 "F.SilkS" user "Ref Des/Silkscreen Top")
		(7 "B.SilkS" user "Ref Des/Silkscreen Bottom")
		(1 "F.Mask" user "Board Geometry/Soldermask Top")
		(3 "B.Mask" user "Board Geometry/Soldermask Bottom")
		(17 "Dwgs.User" user "User.Drawings")
		(19 "Cmts.User" user "User.Comments")
		(21 "Eco1.User" user "User.Eco1")
		(23 "Eco2.User" user "User.Eco2")
		(25 "Edge.Cuts" user "Board Geometry/Outline")
		(27 "Margin" user)
		(31 "F.CrtYd" user "Package Geometry/Place Bound Top")
		(29 "B.CrtYd" user "Package Geometry/Place Bound Bottom")
		(35 "F.Fab" user "Ref Des/Assembly Top")
		(33 "B.Fab" user "Ref Des/Assembly Bottom")
	)
	(footprint ""
		(layer "F.Cu")
		(at 7.42188 -56.987948)
		(property "Reference" "R2995"
			(at 0 0 0)
			(layer "F.SilkS")
			(hide yes)
			(effects
				(font
					(size 1.27 1.27)
				)
			)
		)
		(property "Value" ""
			(at 0 0 0)
			(layer "F.Fab")
			(effects
				(font
					(size 1.27 1.27)
				)
			)
		)
		(duplicate_pad_numbers_are_jumpers no)
		(fp_line
			(start -0.7874 -0.4064)
			(end 0.7874 -0.4064)
			(stroke
				(width 0.1524)
				(type default)
			)
			(layer "F.SilkS")
		)
		(fp_line
			(start -0.7874 0.4064)
			(end -0.7874 -0.4064)
			(stroke
				(width 0.1524)
				(type default)
			)
			(layer "F.SilkS")
		)
		(fp_line
			(start 0.7874 -0.4064)
			(end 0.7874 0.4064)
			(stroke
				(width 0.1524)
				(type default)
			)
			(layer "F.SilkS")
		)
		(fp_line
			(start 0.7874 0.4064)
			(end -0.7874 0.4064)
			(stroke
				(width 0.1524)
				(type default)
			)
			(layer "F.SilkS")
		)
		(fp_line
			(start -0.67945 -0.305054)
			(end -0.12065 -0.305054)
			(stroke
				(width 0.1)
				(type default)
			)
			(layer "F.Fab")
		)
		(fp_line
			(start -0.67945 0.3048)
			(end -0.67945 -0.305054)
			(stroke
				(width 0.1)
				(type default)
			)
			(layer "F.Fab")
		)
		(fp_line
			(start -0.12065 -0.305054)
			(end -0.12065 -0.2794)
			(stroke
				(width 0.1)
				(type default)
			)
			(layer "F.Fab")
		)
		(fp_line
			(start -0.12065 -0.2794)
			(end 0.12065 -0.2794)
			(stroke
				(width 0.1)
				(type default)
			)
			(layer "F.Fab")
		)
		(fp_line
			(start -0.12065 0.2794)
			(end -0.12065 0.3048)
			(stroke
				(width 0.1)
				(type default)
			)
			(layer "F.Fab")
		)
		(fp_line
			(start -0.12065 0.3048)
			(end -0.67945 0.3048)
			(stroke
				(width 0.1)
				(type default)
			)
			(layer "F.Fab")
		)
		(fp_line
			(start 0.120396 0.2794)
			(end -0.12065 0.2794)
			(stroke
				(width 0.1)
				(type default)
			)
			(layer "F.Fab")
		)
		(fp_line
			(start 0.120396 0.3048)
			(end 0.120396 0.2794)
			(stroke
				(width 0.1)
				(type default)
			)
			(layer "F.Fab")
		)
		(fp_line
			(start 0.12065 -0.3048)
			(end 0.67945 -0.3048)
			(stroke
				(width 0.1)
				(type default)
			)
			(layer "F.Fab")
		)
		(fp_line
			(start 0.12065 -0.2794)
			(end 0.12065 -0.3048)
			(stroke
				(width 0.1)
				(type default)
			)
			(layer "F.Fab")
		)
		(fp_line
			(start 0.67945 -0.3048)
			(end 0.67945 0.3048)
			(stroke
				(width 0.1)
				(type default)
			)
			(layer "F.Fab")
		)
		(fp_line
			(start 0.67945 0.3048)
			(end 0.120396 0.3048)
			(stroke
				(width 0.1)
				(type default)
			)
			(layer "F.Fab")
		)
		(pad "1" smd circle
			(at -0.40005 0)
			(size 0 0)
			(layers "F.Cu" "F.Mask" "F.Paste")
			(net "SMB_SML1_PMBUS_3V3AUX_PCH_SCL")
		)
		(pad "2" smd circle
			(at 0.40005 0)
			(size 0 0)
			(layers "F.Cu" "F.Mask" "F.Paste")
			(net "SMB_SML1_PMBUS_HSC_SCL_R3")
		)
	)
	(footprint ""
		(layer "F.Cu")
		(at 397.403066 -166.475664)
		(property "Reference" "PR592"
			(at 0 0 0)
			(layer "F.SilkS")
			(hide yes)
			(effects
				(font
					(size 1.27 1.27)
				)
			)
		)
		(property "Value" ""
			(at 0 0 0)
			(layer "F.Fab")
			(effects
				(font
					(size 1.27 1.27)
				)
			)
		)
		(duplicate_pad_numbers_are_jumpers no)
		(fp_line
			(start -0.7874 -0.4064)
			(end 0.7874 -0.4064)
			(stroke
				(width 0.1524)
				(type default)
			)
			(layer "F.SilkS")
		)
		(fp_line
			(start -0.7874 0.4064)
			(end -0.7874 -0.4064)
			(stroke
				(width 0.1524)
				(type default)
			)
			(layer "F.SilkS")
		)
		(fp_line
			(start 0.7874 -0.4064)
			(end 0.7874 0.4064)
			(stroke
				(width 0.1524)
				(type default)
			)
			(layer "F.SilkS")
		)
		(fp_line
			(start 0.7874 0.4064)
			(end -0.7874 0.4064)
			(stroke
				(width 0.1524)
				(type default)
			)
			(layer "F.SilkS")
		)
		(fp_line
			(start -0.67945 -0.305054)
			(end -0.12065 -0.305054)
			(stroke
				(width 0.1)
				(type default)
			)
			(layer "F.Fab")
		)
		(fp_line
			(start -0.67945 0.3048)
			(end -0.67945 -0.305054)
			(stroke
				(width 0.1)
				(type default)
			)
			(layer "F.Fab")
		)
		(fp_line
			(start -0.12065 -0.305054)
			(end -0.12065 -0.2794)
			(stroke
				(width 0.1)
				(type default)
			)
			(layer "F.Fab")
		)
		(fp_line
			(start -0.12065 -0.2794)
			(end 0.12065 -0.2794)
			(stroke
				(width 0.1)
				(type default)
			)
			(layer "F.Fab")
		)
		(fp_line
			(start -0.12065 0.2794)
			(end -0.12065 0.3048)
			(stroke
				(width 0.1)
				(type default)
			)
			(layer "F.Fab")
		)
		(fp_line
			(start -0.12065 0.3048)
			(end -0.67945 0.3048)
			(stroke
				(width 0.1)
				(type default)
			)
			(layer "F.Fab")
		)
		(fp_line
			(start 0.120396 0.2794)
			(end -0.12065 0.2794)
			(stroke
				(width 0.1)
				(type default)
			)
			(layer "F.Fab")
		)
		(fp_line
			(start 0.120396 0.3048)
			(end 0.120396 0.2794)
			(stroke
				(width 0.1)
				(type default)
			)
			(layer "F.Fab")
		)
		(fp_line
			(start 0.12065 -0.3048)
			(end 0.67945 -0.3048)
			(stroke
				(width 0.1)
				(type default)
			)
			(layer "F.Fab")
		)
		(fp_line
			(start 0.12065 -0.2794)
			(end 0.12065 -0.3048)
			(stroke
				(width 0.1)
				(type default)
			)
			(layer "F.Fab")
		)
		(fp_line
			(start 0.67945 -0.3048)
			(end 0.67945 0.3048)
			(stroke
				(width 0.1)
				(type default)
			)
			(layer "F.Fab")
		)
		(fp_line
			(start 0.67945 0.3048)
			(end 0.120396 0.3048)
			(stroke
				(width 0.1)
				(type default)
			)
			(layer "F.Fab")
		)
		(pad "1" smd circle
			(at -0.40005 0)
			(size 0 0)
			(layers "F.Cu" "F.Mask" "F.Paste")
			(net "VSENSE_PVCCD_HV_CPU0_DP")
		)
		(pad "2" smd circle
			(at 0.40005 0)
			(size 0 0)
			(layers "F.Cu" "F.Mask" "F.Paste")
			(net "PVCCD_HV_CPU0")
		)
	)
)
